FILE_TYPE=LIBRARY_PARTS;
primitive 'AP331AWG7';
  pin
    'IN+':
      PIN_NUMBER='(3)';
      INPUT_LOAD='(-0.01,0.01)';
    'IN-':
      PIN_NUMBER='(1)';
      INPUT_LOAD='(-0.01,0.01)';
    'OUTPUT':
      PIN_NUMBER='(4)';
      OUTPUT_LOAD='(1.0,-1.0)';
    'VCC':
      PIN_NUMBER='(5)';
      PINUSE='POWER';
      NO_LOAD_CHECK='Both';
      NO_IO_CHECK='Both';
      NO_ASSERT_CHECK='TRUE';
      NO_DIR_CHECK='TRUE';
      ALLOW_CONNECT='TRUE';
    'GND':
      PIN_NUMBER='(2)';
      PINUSE='POWER';
      NO_LOAD_CHECK='Both';
      NO_IO_CHECK='Both';
      NO_ASSERT_CHECK='TRUE';
      NO_DIR_CHECK='TRUE';
      ALLOW_CONNECT='TRUE';
  end_pin;
  body
    PART_NAME='AP331AWG7';
    BODY_NAME='AP331AWG7';
    PHYS_DES_PREFIX='U';
    CLASS='IC';
  end_body;
end_primitive;

END.
